FILE_TYPE = CONNECTIVITY;
{Allegro Design Entry HDL 16.6-p007 (v16-6-112F) 10/10/2012}
"PAGE_NUMBER" = 165;
0"NC";
1"GND\g";
2"GND\g";
3"GND\g";
4"P3V3_STBY\g";
5"P3V3_STBY\g";
6"P3V3_STBY\g";
7"GND\g";
8"GND\g";
9"P3V3_STBY\g";
10"IRQ_VM_INT_N";
11"IRQ_VM_INT_R_N";
12"P3V3_FB_ADC128_VCC"VOLTAGE"+3.3V";
13"TP_ADC128_VREF";
14"SMB_SENSOR_PCH_STBY_LVC3_SCL";
15"SMB_SENSOR_PCH_STBY_LVC3_SDA";
16"A_P3V_BAT_SCALED";
17"A_P5V_STBY_SCALED";
18"A_P3V3_STBY_SCALED";
19"A_PVNN_STBY_PCH_SENSOR";
20"A_P1V05_STBY_PCH_SENSOR";
21"A_P12V_STBY_SCALED";
22"A_P5V_SCALED";
23"A_P3V3_SCALED";
24"FM_ADC128_A1";
25"FM_ADC128_A0";
%"ADC128D818"
"1","(-4325,2625)","0","mstr_digital","I52";
;
CDS_SEC"1"
PACK_TYPE"SM"
BOM_COST"SM_HM"
SEC_TYPE"SM"
SEC"1"
CDS_LOCATION"EU9G1"
ROOM"HEC_VOLT_MONITOR"
CDS_LIB"mstr_digital"
LOCATION"EU9G1"
MATERIAL"IC"
PART_NUMBER"H63642-001";
"SCL"
$PN"3"14;
"VP"
$PN"5"12;
"A1"
$PN"8"24;
"SDA"
$PN"2"15;
"VREF"
$PN"1"13;
"A0"
$PN"7"25;
"IN7"
$PN"9"16;
"IN5"
$PN"11"18;
"IN6"
$PN"10"17;
"IN4"
$PN"12"19;
"IN3"
$PN"13"20;
"IN2"
$PN"14"21;
"IN0"
$PN"16"23;
"IN1"
$PN"15"22;
"INT_N"
$PN"6"11;
"GND"
$PN"4"7;
%"RES"
"2","(-6275,2350)","2","mstr_discrete","I55";
;
$SEC"1"
CDS_SEC"1"
BOM_COST"SM_HM"
ROOM"HEC_VOLT_MONITOR"
CDS_LIB"mstr_discrete"
CDS_LOCATION"R1U45"
TOLERANCE"1%"
LOCATION"R1U45"
PART_NUMBER"G21796-072"
VALUE"4.75K"
PACK_TYPE"0402"
MATERIAL"CHIP"
WATTAGE"1/16W";
"A"
$PN"1"25;
"B"
$PN"2"1;
%"RES"
"2","(-6650,2350)","2","mstr_discrete","I56";
;
CDS_LIB"mstr_discrete"
BOM_COST"SM_HM"
CDS_SEC"1"
$SEC"1"
ROOM"HEC_VOLT_MONITOR"
CDS_LOCATION"R1U48"
LOCATION"R1U48"
PART_NUMBER"G21796-072"
VALUE"4.75K"
TOLERANCE"1%"
PACK_TYPE"0402"
MATERIAL"CHIP"
WATTAGE"1/16W";
"A"
$PN"1"24;
"B"
$PN"2"2;
%"RES"
"2","(-6275,2850)","0","mstr_discrete","I57";
;
$SEC"1"
CDS_SEC"1"
BOM_COST"SM_HM"
CDS_LOCATION"R9G23"
ROOM"HEC_VOLT_MONITOR"
CDS_LIB"mstr_discrete"
MATERIAL"EMPTY"
LOCATION"R9G23"
PART_NUMBER"G21796-072"
VALUE"4.75K"
PACK_TYPE"0402"
WATTAGE"1/16W"
TOLERANCE"1%";
"A"
$PN"1"5;
"B"
$PN"2"25;
%"RES"
"2","(-6650,2850)","0","mstr_discrete","I58";
;
$SEC"1"
CDS_SEC"1"
BOM_COST"SM_HM"
CDS_LOCATION"R9G25"
ROOM"HEC_VOLT_MONITOR"
CDS_LIB"mstr_discrete"
PART_NUMBER"G21796-072"
LOCATION"R9G25"
VALUE"4.75K"
WATTAGE"1/16W"
TOLERANCE"1%"
MATERIAL"EMPTY"
PACK_TYPE"0402";
"A"
$PN"1"6;
"B"
$PN"2"24;
%"GND"
"1","(-6275,2100)","0","mstr_symbols","I59";
;
SIZE"1B"
HDL_POWER"GND"
BODY_TYPE"PLUMBING"
CDS_LIB"mstr_symbols"
VOLTAGE"0.0V";
"A\NAC"1;
%"GND"
"1","(-6650,2100)","0","mstr_symbols","I60";
;
HDL_POWER"GND"
CDS_LIB"mstr_symbols"
SIZE"1B"
VOLTAGE"0.0V"
BODY_TYPE"PLUMBING";
"A\NAC"2;
%"CAP_A"
"1","(-5050,3525)","0","dev_discrete","I61";
;
BOM_COST"SM_HM"
CDS_SEC"1"
$SEC"1"
ROOM"HEC_VOLT_MONITOR"
CDS_LOCATION"C9G19"
CDS_LIB"dev_discrete"
LOCATION"C9G19"
VALUE"0.1UF"
PART_NUMBER"A36096-030"
PACK_TYPE"0402V"
TOLERANCE"10%"
VOLTAGE"16V"
MATERIAL"X7R";
"B"
$PN"2"3;
"A"
$PN"1"12;
%"GND"
"1","(-5050,3250)","0","mstr_symbols","I62";
;
HDL_POWER"GND"
VOLTAGE"0.0V"
SIZE"1B"
CDS_LIB"mstr_symbols"
BODY_TYPE"PLUMBING";
"A\NAC"3;
%"P3V3_STBY"
"1","(-5750,3950)","0","mstr_symbols","I63";
;
VOLTAGE"3.3V"
CDS_LIB"mstr_symbols"
SIZE"1B"
BODY_TYPE"PLUMBING"
HDL_POWER"P3V3_STBY";
"G\NAC"4;
%"P3V3_STBY"
"1","(-6275,3100)","0","mstr_symbols","I64";
;
SIZE"1B"
CDS_LIB"mstr_symbols"
VOLTAGE"3.3V"
BODY_TYPE"PLUMBING"
HDL_POWER"P3V3_STBY";
"G\NAC"5;
%"P3V3_STBY"
"1","(-6650,3100)","0","mstr_symbols","I65";
;
CDS_LIB"mstr_symbols"
SIZE"1B"
VOLTAGE"3.3V"
BODY_TYPE"PLUMBING"
HDL_POWER"P3V3_STBY";
"G\NAC"6;
%"GND"
"1","(-3925,1900)","0","mstr_symbols","I66";
;
HDL_POWER"GND"
SIZE"1B"
CDS_LIB"mstr_symbols"
VOLTAGE"0.0V"
BODY_TYPE"PLUMBING";
"A\NAC"7;
%"CAP"
"1","(-5325,3525)","0","mstr_discrete","I67";
;
$SEC"1"
CDS_SEC"1"
BOM_COST"SM_HM"
ROOM"HEC_VOLT_MONITOR"
CDS_LOCATION"C1U20"
CDS_LIB"mstr_discrete"
PART_NUMBER"G10601-001"
LOCATION"C1U20"
VALUE"10UF"
TOLERANCE"10%"
VOLTAGE"16V"
MATERIAL"X7R"
PACK_TYPE"0805";
"A"
$PN"1"12;
"B"
$PN"2"8;
%"GND"
"1","(-5325,3250)","0","mstr_symbols","I68";
;
HDL_POWER"GND"
VOLTAGE"0.0V"
CDS_LIB"mstr_symbols"
SIZE"1B"
BODY_TYPE"PLUMBING";
"A\NAC"8;
%"RES"
"2","(-3650,3375)","0","mstr_discrete","I69";
;
CDS_SEC"1"
BOM_COST"SM_HM"
SEC_TYPE"0402"
SEC"1"
ROOM"HEC_VOLT_MONITOR"
CDS_LIB"mstr_discrete"
CDS_LOCATION"R9G21"
LOCATION"R9G21"
PART_NUMBER"G21796-072"
VALUE"4.75K"
TOLERANCE"1%"
PACK_TYPE"0402"
MATERIAL"CHIP"
WATTAGE"1/16W";
"A"
$PN"1"9;
"B"
$PN"2"11;
%"P3V3_STBY"
"1","(-3650,3725)","0","mstr_symbols","I70";
;
VOLTAGE"3.3V"
CDS_LIB"mstr_symbols"
SIZE"1B"
BODY_TYPE"PLUMBING"
HDL_POWER"P3V3_STBY";
"G\NAC"9;
%"FERRITE"
"1","(-5525,3750)","0","mstr_discrete","I79";
;
CDS_SEC"1"
SEC"1"
ROOM"HEC_VOLT_MONITOR"
SEC_TYPE"SMLF"
BOM_COST"SM_HM"
CDS_LOCATION"FB1U2"
CDS_LIB"mstr_discrete"
PACK_TYPE"SMLF"
PART_NUMBER"693286-001"
LOCATION"FB1U2"
MATERIAL"FB"
VALUE"60";
"A"
$PN"1"4;
"B"
$PN"2"12;
%"RES"
"1","(-3075,3025)","0","mstr_discrete","I81";
;
CDS_SEC"1"
SEC_TYPE"0402"
SEC"1"
CDS_LOCATION"R1U40"
CDS_LIB"mstr_discrete"
PACK_TYPE"0402"
LOCATION"R1U40"
PART_NUMBER"G21796-074"
TOLERANCE"1%"
MATERIAL"CHIP"
VALUE"33.2"
WATTAGE"1/16W";
"B"
$PN"2"10;
"A"
$PN"1"11;
END.
